(kicad_pcb
	(version 20260206)
	(generator "pcbnew")
	(generator_version "10.0")
	(general
		(thickness 1.6)
		(legacy_teardrops no)
	)
	(paper "A4")
	(title_block
		(title "03242023_DA0F0TMBIJ0_F0T_Motherboard_J_brd_V01_OCP.brd")
		(comment 1 "Grand Teton / footprints 1592-1597 of 6105")
	)
	(layers
		(0 "F.Cu" signal "TOP")
		(4 "In1.Cu" signal "GND")
		(6 "In2.Cu" signal "IN1")
		(8 "In3.Cu" signal "GND1")
		(10 "In4.Cu" signal "IN2")
		(12 "In5.Cu" signal "GND2")
		(14 "In6.Cu" signal "IN3")
		(16 "In7.Cu" signal "GND3")
		(18 "In8.Cu" signal "VCC")
		(20 "In9.Cu" signal "VCC1")
		(22 "In10.Cu" signal "GND4")
		(24 "In11.Cu" signal "IN4")
		(26 "In12.Cu" signal "GND5")
		(28 "In13.Cu" signal "IN5")
		(30 "In14.Cu" signal "GND6")
		(32 "In15.Cu" signal "IN6")
		(34 "In16.Cu" signal "GND7")
		(2 "B.Cu" signal "BOTTOM")
		(9 "F.Adhes" user "F.Adhesive")
		(11 "B.Adhes" user "B.Adhesive")
		(13 "F.Paste" user "Package Geometry/Pastemask Top")
		(15 "B.Paste" user "Package Geometry/Pastemask Bottom")
		(5 "F.SilkS" user "Ref Des/Silkscreen Top")
		(7 "B.SilkS" user "Ref Des/Silkscreen Bottom")
		(1 "F.Mask" user "Board Geometry/Soldermask Top")
		(3 "B.Mask" user "Board Geometry/Soldermask Bottom")
		(17 "Dwgs.User" user "User.Drawings")
		(19 "Cmts.User" user "User.Comments")
		(21 "Eco1.User" user "User.Eco1")
		(23 "Eco2.User" user "User.Eco2")
		(25 "Edge.Cuts" user "Board Geometry/Outline")
		(27 "Margin" user)
		(31 "F.CrtYd" user "Package Geometry/Place Bound Top")
		(29 "B.CrtYd" user "Package Geometry/Place Bound Bottom")
		(35 "F.Fab" user "Ref Des/Assembly Top")
		(33 "B.Fab" user "Ref Des/Assembly Bottom")
	)
	(footprint ""
		(layer "F.Cu")
		(at 119.341138 -355.71049 180)
		(property "Reference" "C2460"
			(at 0 0 180)
			(layer "F.SilkS")
			(hide yes)
			(effects
				(font
					(size 1.27 1.27)
				)
			)
		)
		(property "Value" ""
			(at 0 0 180)
			(layer "F.Fab")
			(effects
				(font
					(size 1.27 1.27)
				)
			)
		)
		(duplicate_pad_numbers_are_jumpers no)
		(fp_line
			(start 0.7874 0.4064)
			(end -0.7874 0.4064)
			(stroke
				(width 0.1524)
				(type default)
			)
			(layer "F.SilkS")
		)
		(fp_line
			(start 0.7874 -0.4064)
			(end 0.7874 0.4064)
			(stroke
				(width 0.1524)
				(type default)
			)
			(layer "F.SilkS")
		)
		(fp_line
			(start -0.7874 0.4064)
			(end -0.7874 -0.4064)
			(stroke
				(width 0.1524)
				(type default)
			)
			(layer "F.SilkS")
		)
		(fp_line
			(start -0.7874 -0.4064)
			(end 0.7874 -0.4064)
			(stroke
				(width 0.1524)
				(type default)
			)
			(layer "F.SilkS")
		)
		(fp_line
			(start 0.67945 0.3048)
			(end 0.120396 0.3048)
			(stroke
				(width 0.1)
				(type default)
			)
			(layer "F.Fab")
		)
		(fp_line
			(start 0.67945 -0.3048)
			(end 0.67945 0.3048)
			(stroke
				(width 0.1)
				(type default)
			)
			(layer "F.Fab")
		)
		(fp_line
			(start 0.12065 -0.2794)
			(end 0.12065 -0.3048)
			(stroke
				(width 0.1)
				(type default)
			)
			(layer "F.Fab")
		)
		(fp_line
			(start 0.12065 -0.3048)
			(end 0.67945 -0.3048)
			(stroke
				(width 0.1)
				(type default)
			)
			(layer "F.Fab")
		)
		(fp_line
			(start 0.120396 0.3048)
			(end 0.120396 0.2794)
			(stroke
				(width 0.1)
				(type default)
			)
			(layer "F.Fab")
		)
		(fp_line
			(start 0.120396 0.2794)
			(end -0.12065 0.2794)
			(stroke
				(width 0.1)
				(type default)
			)
			(layer "F.Fab")
		)
		(fp_line
			(start -0.12065 0.3048)
			(end -0.67945 0.3048)
			(stroke
				(width 0.1)
				(type default)
			)
			(layer "F.Fab")
		)
		(fp_line
			(start -0.12065 0.2794)
			(end -0.12065 0.3048)
			(stroke
				(width 0.1)
				(type default)
			)
			(layer "F.Fab")
		)
		(fp_line
			(start -0.12065 -0.2794)
			(end 0.12065 -0.2794)
			(stroke
				(width 0.1)
				(type default)
			)
			(layer "F.Fab")
		)
		(fp_line
			(start -0.12065 -0.305054)
			(end -0.12065 -0.2794)
			(stroke
				(width 0.1)
				(type default)
			)
			(layer "F.Fab")
		)
		(fp_line
			(start -0.67945 0.3048)
			(end -0.67945 -0.305054)
			(stroke
				(width 0.1)
				(type default)
			)
			(layer "F.Fab")
		)
		(fp_line
			(start -0.67945 -0.305054)
			(end -0.12065 -0.305054)
			(stroke
				(width 0.1)
				(type default)
			)
			(layer "F.Fab")
		)
		(pad "1" smd circle
			(at -0.40005 0 180)
			(size 0 0)
			(layers "F.Cu" "F.Mask" "F.Paste")
			(net "PWRGD_PVPP_HBM_CPU1_R")
		)
		(pad "2" smd circle
			(at 0.40005 0 180)
			(size 0 0)
			(layers "F.Cu" "F.Mask" "F.Paste")
			(net "GND")
		)
	)
	(footprint ""
		(layer "F.Cu")
		(at 204.93736 -115.534948 180)
		(property "Reference" "R4143"
			(at 0 0 180)
			(layer "F.SilkS")
			(hide yes)
			(effects
				(font
					(size 1.27 1.27)
				)
			)
		)
		(property "Value" ""
			(at 0 0 180)
			(layer "F.Fab")
			(effects
				(font
					(size 1.27 1.27)
				)
			)
		)
		(duplicate_pad_numbers_are_jumpers no)
		(fp_line
			(start 0.7874 0.4064)
			(end -0.7874 0.4064)
			(stroke
				(width 0.1524)
				(type default)
			)
			(layer "F.SilkS")
		)
		(fp_line
			(start 0.7874 -0.4064)
			(end 0.7874 0.4064)
			(stroke
				(width 0.1524)
				(type default)
			)
			(layer "F.SilkS")
		)
		(fp_line
			(start -0.7874 0.4064)
			(end -0.7874 -0.4064)
			(stroke
				(width 0.1524)
				(type default)
			)
			(layer "F.SilkS")
		)
		(fp_line
			(start -0.7874 -0.4064)
			(end 0.7874 -0.4064)
			(stroke
				(width 0.1524)
				(type default)
			)
			(layer "F.SilkS")
		)
		(fp_line
			(start 0.67945 0.3048)
			(end 0.120396 0.3048)
			(stroke
				(width 0.1)
				(type default)
			)
			(layer "F.Fab")
		)
		(fp_line
			(start 0.67945 -0.3048)
			(end 0.67945 0.3048)
			(stroke
				(width 0.1)
				(type default)
			)
			(layer "F.Fab")
		)
		(fp_line
			(start 0.12065 -0.2794)
			(end 0.12065 -0.3048)
			(stroke
				(width 0.1)
				(type default)
			)
			(layer "F.Fab")
		)
		(fp_line
			(start 0.12065 -0.3048)
			(end 0.67945 -0.3048)
			(stroke
				(width 0.1)
				(type default)
			)
			(layer "F.Fab")
		)
		(fp_line
			(start 0.120396 0.3048)
			(end 0.120396 0.2794)
			(stroke
				(width 0.1)
				(type default)
			)
			(layer "F.Fab")
		)
		(fp_line
			(start 0.120396 0.2794)
			(end -0.12065 0.2794)
			(stroke
				(width 0.1)
				(type default)
			)
			(layer "F.Fab")
		)
		(fp_line
			(start -0.12065 0.3048)
			(end -0.67945 0.3048)
			(stroke
				(width 0.1)
				(type default)
			)
			(layer "F.Fab")
		)
		(fp_line
			(start -0.12065 0.2794)
			(end -0.12065 0.3048)
			(stroke
				(width 0.1)
				(type default)
			)
			(layer "F.Fab")
		)
		(fp_line
			(start -0.12065 -0.2794)
			(end 0.12065 -0.2794)
			(stroke
				(width 0.1)
				(type default)
			)
			(layer "F.Fab")
		)
		(fp_line
			(start -0.12065 -0.305054)
			(end -0.12065 -0.2794)
			(stroke
				(width 0.1)
				(type default)
			)
			(layer "F.Fab")
		)
		(fp_line
			(start -0.67945 0.3048)
			(end -0.67945 -0.305054)
			(stroke
				(width 0.1)
				(type default)
			)
			(layer "F.Fab")
		)
		(fp_line
			(start -0.67945 -0.305054)
			(end -0.12065 -0.305054)
			(stroke
				(width 0.1)
				(type default)
			)
			(layer "F.Fab")
		)
		(pad "1" smd circle
			(at -0.40005 0 180)
			(size 0 0)
			(layers "F.Cu" "F.Mask" "F.Paste")
			(net "GPU_3V3IO_RSVD0_FFU_ISO")
		)
		(pad "2" smd circle
			(at 0.40005 0 180)
			(size 0 0)
			(layers "F.Cu" "F.Mask" "F.Paste")
			(net "GPU_3V3IO_RSVD0_FFU_ISO_R")
		)
	)
	(footprint ""
		(layer "F.Cu")
		(at 369.259358 -92.962984 90)
		(property "Reference" "R482"
			(at 0 0 90)
			(layer "F.SilkS")
			(hide yes)
			(effects
				(font
					(size 1.27 1.27)
				)
			)
		)
		(property "Value" ""
			(at 0 0 90)
			(layer "F.Fab")
			(effects
				(font
					(size 1.27 1.27)
				)
			)
		)
		(duplicate_pad_numbers_are_jumpers no)
		(fp_line
			(start 0.7874 -0.4064)
			(end 0.7874 0.4064)
			(stroke
				(width 0.1524)
				(type default)
			)
			(layer "F.SilkS")
		)
		(fp_line
			(start -0.7874 -0.4064)
			(end 0.7874 -0.4064)
			(stroke
				(width 0.1524)
				(type default)
			)
			(layer "F.SilkS")
		)
		(fp_line
			(start 0.7874 0.4064)
			(end -0.7874 0.4064)
			(stroke
				(width 0.1524)
				(type default)
			)
			(layer "F.SilkS")
		)
		(fp_line
			(start -0.7874 0.4064)
			(end -0.7874 -0.4064)
			(stroke
				(width 0.1524)
				(type default)
			)
			(layer "F.SilkS")
		)
		(fp_line
			(start -0.12065 -0.305054)
			(end -0.12065 -0.2794)
			(stroke
				(width 0.1)
				(type default)
			)
			(layer "F.Fab")
		)
		(fp_line
			(start -0.67945 -0.305054)
			(end -0.12065 -0.305054)
			(stroke
				(width 0.1)
				(type default)
			)
			(layer "F.Fab")
		)
		(fp_line
			(start 0.67945 -0.3048)
			(end 0.67945 0.3048)
			(stroke
				(width 0.1)
				(type default)
			)
			(layer "F.Fab")
		)
		(fp_line
			(start 0.12065 -0.3048)
			(end 0.67945 -0.3048)
			(stroke
				(width 0.1)
				(type default)
			)
			(layer "F.Fab")
		)
		(fp_line
			(start 0.12065 -0.2794)
			(end 0.12065 -0.3048)
			(stroke
				(width 0.1)
				(type default)
			)
			(layer "F.Fab")
		)
		(fp_line
			(start -0.12065 -0.2794)
			(end 0.12065 -0.2794)
			(stroke
				(width 0.1)
				(type default)
			)
			(layer "F.Fab")
		)
		(fp_line
			(start 0.120396 0.2794)
			(end -0.12065 0.2794)
			(stroke
				(width 0.1)
				(type default)
			)
			(layer "F.Fab")
		)
		(fp_line
			(start -0.12065 0.2794)
			(end -0.12065 0.3048)
			(stroke
				(width 0.1)
				(type default)
			)
			(layer "F.Fab")
		)
		(fp_line
			(start 0.67945 0.3048)
			(end 0.120396 0.3048)
			(stroke
				(width 0.1)
				(type default)
			)
			(layer "F.Fab")
		)
		(fp_line
			(start 0.120396 0.3048)
			(end 0.120396 0.2794)
			(stroke
				(width 0.1)
				(type default)
			)
			(layer "F.Fab")
		)
		(fp_line
			(start -0.12065 0.3048)
			(end -0.67945 0.3048)
			(stroke
				(width 0.1)
				(type default)
			)
			(layer "F.Fab")
		)
		(fp_line
			(start -0.67945 0.3048)
			(end -0.67945 -0.305054)
			(stroke
				(width 0.1)
				(type default)
			)
			(layer "F.Fab")
		)
		(pad "1" smd circle
			(at -0.40005 0 90)
			(size 0 0)
			(layers "F.Cu" "F.Mask" "F.Paste")
			(net "JTAG_DBP_PREQ_N")
		)
		(pad "2" smd circle
			(at 0.40005 0 90)
			(size 0 0)
			(layers "F.Cu" "F.Mask" "F.Paste")
			(net "JTAG_DBP_PREQ_R_N")
		)
	)
	(footprint ""
		(layer "F.Cu")
		(at 212.118956 -30.276292 -90)
		(property "Reference" "R3561"
			(at 0 0 270)
			(layer "F.SilkS")
			(hide yes)
			(effects
				(font
					(size 1.27 1.27)
				)
			)
		)
		(property "Value" ""
			(at 0 0 270)
			(layer "F.Fab")
			(effects
				(font
					(size 1.27 1.27)
				)
			)
		)
		(duplicate_pad_numbers_are_jumpers no)
		(fp_line
			(start -0.7874 0.4064)
			(end -0.7874 -0.4064)
			(stroke
				(width 0.1524)
				(type default)
			)
			(layer "F.SilkS")
		)
		(fp_line
			(start 0.7874 0.4064)
			(end -0.7874 0.4064)
			(stroke
				(width 0.1524)
				(type default)
			)
			(layer "F.SilkS")
		)
		(fp_line
			(start -0.7874 -0.4064)
			(end 0.7874 -0.4064)
			(stroke
				(width 0.1524)
				(type default)
			)
			(layer "F.SilkS")
		)
		(fp_line
			(start 0.7874 -0.4064)
			(end 0.7874 0.4064)
			(stroke
				(width 0.1524)
				(type default)
			)
			(layer "F.SilkS")
		)
		(fp_line
			(start -0.67945 0.3048)
			(end -0.67945 -0.305054)
			(stroke
				(width 0.1)
				(type default)
			)
			(layer "F.Fab")
		)
		(fp_line
			(start -0.12065 0.3048)
			(end -0.67945 0.3048)
			(stroke
				(width 0.1)
				(type default)
			)
			(layer "F.Fab")
		)
		(fp_line
			(start 0.120396 0.3048)
			(end 0.120396 0.2794)
			(stroke
				(width 0.1)
				(type default)
			)
			(layer "F.Fab")
		)
		(fp_line
			(start 0.67945 0.3048)
			(end 0.120396 0.3048)
			(stroke
				(width 0.1)
				(type default)
			)
			(layer "F.Fab")
		)
		(fp_line
			(start -0.12065 0.2794)
			(end -0.12065 0.3048)
			(stroke
				(width 0.1)
				(type default)
			)
			(layer "F.Fab")
		)
		(fp_line
			(start 0.120396 0.2794)
			(end -0.12065 0.2794)
			(stroke
				(width 0.1)
				(type default)
			)
			(layer "F.Fab")
		)
		(fp_line
			(start -0.12065 -0.2794)
			(end 0.12065 -0.2794)
			(stroke
				(width 0.1)
				(type default)
			)
			(layer "F.Fab")
		)
		(fp_line
			(start 0.12065 -0.2794)
			(end 0.12065 -0.3048)
			(stroke
				(width 0.1)
				(type default)
			)
			(layer "F.Fab")
		)
		(fp_line
			(start 0.12065 -0.3048)
			(end 0.67945 -0.3048)
			(stroke
				(width 0.1)
				(type default)
			)
			(layer "F.Fab")
		)
		(fp_line
			(start 0.67945 -0.3048)
			(end 0.67945 0.3048)
			(stroke
				(width 0.1)
				(type default)
			)
			(layer "F.Fab")
		)
		(fp_line
			(start -0.67945 -0.305054)
			(end -0.12065 -0.305054)
			(stroke
				(width 0.1)
				(type default)
			)
			(layer "F.Fab")
		)
		(fp_line
			(start -0.12065 -0.305054)
			(end -0.12065 -0.2794)
			(stroke
				(width 0.1)
				(type default)
			)
			(layer "F.Fab")
		)
		(pad "1" smd circle
			(at -0.40005 0 270)
			(size 0 0)
			(layers "F.Cu" "F.Mask" "F.Paste")
			(net "P12V_SCM_ADC_ALERT_R")
		)
		(pad "2" smd circle
			(at 0.40005 0 270)
			(size 0 0)
			(layers "F.Cu" "F.Mask" "F.Paste")
			(net "P12V_SCM_ADC_ALERT")
		)
	)
	(footprint ""
		(layer "F.Cu")
		(at 70.358 -114.772948 180)
		(property "Reference" "R4270"
			(at 0 0 180)
			(layer "F.SilkS")
			(hide yes)
			(effects
				(font
					(size 1.27 1.27)
				)
			)
		)
		(property "Value" ""
			(at 0 0 180)
			(layer "F.Fab")
			(effects
				(font
					(size 1.27 1.27)
				)
			)
		)
		(duplicate_pad_numbers_are_jumpers no)
		(fp_line
			(start 0.7874 0.4064)
			(end -0.7874 0.4064)
			(stroke
				(width 0.1524)
				(type default)
			)
			(layer "F.SilkS")
		)
		(fp_line
			(start 0.7874 -0.4064)
			(end 0.7874 0.4064)
			(stroke
				(width 0.1524)
				(type default)
			)
			(layer "F.SilkS")
		)
		(fp_line
			(start -0.7874 0.4064)
			(end -0.7874 -0.4064)
			(stroke
				(width 0.1524)
				(type default)
			)
			(layer "F.SilkS")
		)
		(fp_line
			(start -0.7874 -0.4064)
			(end 0.7874 -0.4064)
			(stroke
				(width 0.1524)
				(type default)
			)
			(layer "F.SilkS")
		)
		(fp_line
			(start 0.67945 0.3048)
			(end 0.120396 0.3048)
			(stroke
				(width 0.1)
				(type default)
			)
			(layer "F.Fab")
		)
		(fp_line
			(start 0.67945 -0.3048)
			(end 0.67945 0.3048)
			(stroke
				(width 0.1)
				(type default)
			)
			(layer "F.Fab")
		)
		(fp_line
			(start 0.12065 -0.2794)
			(end 0.12065 -0.3048)
			(stroke
				(width 0.1)
				(type default)
			)
			(layer "F.Fab")
		)
		(fp_line
			(start 0.12065 -0.3048)
			(end 0.67945 -0.3048)
			(stroke
				(width 0.1)
				(type default)
			)
			(layer "F.Fab")
		)
		(fp_line
			(start 0.120396 0.3048)
			(end 0.120396 0.2794)
			(stroke
				(width 0.1)
				(type default)
			)
			(layer "F.Fab")
		)
		(fp_line
			(start 0.120396 0.2794)
			(end -0.12065 0.2794)
			(stroke
				(width 0.1)
				(type default)
			)
			(layer "F.Fab")
		)
		(fp_line
			(start -0.12065 0.3048)
			(end -0.67945 0.3048)
			(stroke
				(width 0.1)
				(type default)
			)
			(layer "F.Fab")
		)
		(fp_line
			(start -0.12065 0.2794)
			(end -0.12065 0.3048)
			(stroke
				(width 0.1)
				(type default)
			)
			(layer "F.Fab")
		)
		(fp_line
			(start -0.12065 -0.2794)
			(end 0.12065 -0.2794)
			(stroke
				(width 0.1)
				(type default)
			)
			(layer "F.Fab")
		)
		(fp_line
			(start -0.12065 -0.305054)
			(end -0.12065 -0.2794)
			(stroke
				(width 0.1)
				(type default)
			)
			(layer "F.Fab")
		)
		(fp_line
			(start -0.67945 0.3048)
			(end -0.67945 -0.305054)
			(stroke
				(width 0.1)
				(type default)
			)
			(layer "F.Fab")
		)
		(fp_line
			(start -0.67945 -0.305054)
			(end -0.12065 -0.305054)
			(stroke
				(width 0.1)
				(type default)
			)
			(layer "F.Fab")
		)
		(pad "1" smd circle
			(at -0.40005 0 180)
			(size 0 0)
			(layers "F.Cu" "F.Mask" "F.Paste")
			(net "P3V3_AUX")
		)
		(pad "2" smd circle
			(at 0.40005 0 180)
			(size 0 0)
			(layers "F.Cu" "F.Mask" "F.Paste")
			(net "SMB_VR_SENSOR_3V3AUX_SDA")
		)
	)
	(footprint ""
		(layer "F.Cu")
		(at 303.2506 -424.08475 90)
		(property "Reference" "Q128"
			(at -7.87908 5.816092 90)
			(unlocked yes)
			(layer "F.SilkS")
			(effects
				(font
					(size 0.7874 0.5842)
					(thickness 0.1524)
				)
				(justify left)
			)
		)
		(property "Value" ""
			(at 0 0 90)
			(layer "F.Fab")
			(effects
				(font
					(size 1.27 1.27)
				)
			)
		)
		(duplicate_pad_numbers_are_jumpers no)
		(fp_line
			(start 1.332738 -1.100074)
			(end 1.332738 1.100074)
			(stroke
				(width 0.1524)
				(type default)
			)
			(layer "F.SilkS")
		)
		(fp_line
			(start 0.4826 -1.100074)
			(end 1.332738 -1.100074)
			(stroke
				(width 0.1524)
				(type default)
			)
			(layer "F.SilkS")
		)
		(fp_line
			(start -0.4826 -1.100074)
			(end 0 -0.541274)
			(stroke
				(width 0.1524)
				(type default)
			)
			(layer "F.SilkS")
		)
		(fp_line
			(start -1.332738 -1.100074)
			(end -0.4826 -1.100074)
			(stroke
				(width 0.1524)
				(type default)
			)
			(layer "F.SilkS")
		)
		(fp_line
			(start 0 -0.541274)
			(end 0.4826 -1.100074)
			(stroke
				(width 0.1524)
				(type default)
			)
			(layer "F.SilkS")
		)
		(fp_line
			(start 1.332738 1.100074)
			(end -1.332738 1.100074)
			(stroke
				(width 0.1524)
				(type default)
			)
			(layer "F.SilkS")
		)
		(fp_line
			(start -1.332738 1.100074)
			(end -1.332738 -1.100074)
			(stroke
				(width 0.1524)
				(type default)
			)
			(layer "F.SilkS")
		)
		(fp_poly
			(pts
				(xy -2.37236 -1.427734) (xy -1.670304 -1.076706) (xy -2.37236 -0.725678)
			)
			(stroke
				(width 0)
				(type default)
			)
			(fill yes)
			(layer "F.SilkS")
		)
		(fp_line
			(start 0.674878 -1.100074)
			(end 0.674878 1.100074)
			(stroke
				(width 0.1)
				(type default)
			)
			(layer "F.Fab")
		)
		(fp_line
			(start -0.674878 -1.100074)
			(end 0.674878 -1.100074)
			(stroke
				(width 0.1)
				(type default)
			)
			(layer "F.Fab")
		)
		(fp_line
			(start 0.674878 1.100074)
			(end -0.674878 1.100074)
			(stroke
				(width 0.1)
				(type default)
			)
			(layer "F.Fab")
		)
		(fp_line
			(start -0.674878 1.100074)
			(end -0.674878 -1.100074)
			(stroke
				(width 0.1)
				(type default)
			)
			(layer "F.Fab")
		)
		(fp_poly
			(pts
				(xy -2.2352 -0.298958) (xy -2.2352 -1.001014) (xy -1.533144 -0.649986)
			)
			(stroke
				(width 0)
				(type default)
			)
			(fill yes)
			(layer "F.Fab")
		)
		(pad "1" smd rect
			(at -0.94996 -0.649986 180)
			(size 0.4318 0.508)
			(layers "F.Cu" "F.Mask" "F.Paste")
			(net "GND")
		)
		(pad "2" smd rect
			(at -0.94996 0 180)
			(size 0.4318 0.508)
			(layers "F.Cu" "F.Mask" "F.Paste")
			(net "GPU_3V3IO_RSVD0_FFU")
		)
		(pad "3" smd rect
			(at -0.94996 0.649986 180)
			(size 0.4318 0.508)
			(layers "F.Cu" "F.Mask" "F.Paste")
			(net "GPU_3V3IO_RSVD0_FFU_ISO")
		)
		(pad "4" smd rect
			(at 0.94996 0.649986 180)
			(size 0.4318 0.508)
			(layers "F.Cu" "F.Mask" "F.Paste")
			(net "GND")
		)
		(pad "5" smd rect
			(at 0.94996 0 180)
			(size 0.4318 0.508)
			(layers "F.Cu" "F.Mask" "F.Paste")
			(net "GPU_3V3IO_RSVD0_FFU_N")
		)
		(pad "6" smd rect
			(at 0.94996 -0.649986 180)
			(size 0.4318 0.508)
			(layers "F.Cu" "F.Mask" "F.Paste")
			(net "GPU_3V3IO_RSVD0_FFU_N")
		)
	)
)
